FILE_TYPE=LIBRARY_PARTS;
primitive 'GTL2014PW';
  pin
    'B0':
      PIN_NUMBER='(2)';
      BIDIRECTIONAL='TRUE';
      INPUT_LOAD='(-0.01,0.01)';
      OUTPUT_LOAD='(1.0,-1.0)';
    'B1':
      PIN_NUMBER='(3)';
      BIDIRECTIONAL='TRUE';
      INPUT_LOAD='(-0.01,0.01)';
      OUTPUT_LOAD='(1.0,-1.0)';
    'B2':
      PIN_NUMBER='(5)';
      BIDIRECTIONAL='TRUE';
      INPUT_LOAD='(-0.01,0.01)';
      OUTPUT_LOAD='(1.0,-1.0)';
    'B3':
      PIN_NUMBER='(6)';
      BIDIRECTIONAL='TRUE';
      INPUT_LOAD='(-0.01,0.01)';
      OUTPUT_LOAD='(1.0,-1.0)';
    'GND_2':
      PIN_NUMBER='(11)';
      PINUSE='POWER';
      NO_LOAD_CHECK='Both';
      NO_IO_CHECK='Both';
      NO_ASSERT_CHECK='TRUE';
      NO_DIR_CHECK='TRUE';
      ALLOW_CONNECT='TRUE';
    'GND_1':
      PIN_NUMBER='(8)';
      PINUSE='POWER';
      NO_LOAD_CHECK='Both';
      NO_IO_CHECK='Both';
      NO_ASSERT_CHECK='TRUE';
      NO_DIR_CHECK='TRUE';
      ALLOW_CONNECT='TRUE';
    'GND_0':
      PIN_NUMBER='(7)';
      PINUSE='POWER';
      NO_LOAD_CHECK='Both';
      NO_IO_CHECK='Both';
      NO_ASSERT_CHECK='TRUE';
      NO_DIR_CHECK='TRUE';
      ALLOW_CONNECT='TRUE';
    'A3':
      PIN_NUMBER='(9)';
      BIDIRECTIONAL='TRUE';
      INPUT_LOAD='(-0.01,0.01)';
      OUTPUT_LOAD='(1.0,-1.0)';
    'A2':
      PIN_NUMBER='(10)';
      BIDIRECTIONAL='TRUE';
      INPUT_LOAD='(-0.01,0.01)';
      OUTPUT_LOAD='(1.0,-1.0)';
    'A1':
      PIN_NUMBER='(12)';
      BIDIRECTIONAL='TRUE';
      INPUT_LOAD='(-0.01,0.01)';
      OUTPUT_LOAD='(1.0,-1.0)';
    'A0':
      PIN_NUMBER='(13)';
      BIDIRECTIONAL='TRUE';
      INPUT_LOAD='(-0.01,0.01)';
      OUTPUT_LOAD='(1.0,-1.0)';
    'DIR':
      PIN_NUMBER='(1)';
      INPUT_LOAD='(-0.01,0.01)';
    'VREF':
      PIN_NUMBER='(4)';
      PINUSE='POWER';
      NO_LOAD_CHECK='Both';
      NO_IO_CHECK='Both';
      NO_ASSERT_CHECK='TRUE';
      NO_DIR_CHECK='TRUE';
      ALLOW_CONNECT='TRUE';
    'VCC':
      PIN_NUMBER='(14)';
      PINUSE='POWER';
      NO_LOAD_CHECK='Both';
      NO_IO_CHECK='Both';
      NO_ASSERT_CHECK='TRUE';
      NO_DIR_CHECK='TRUE';
      ALLOW_CONNECT='TRUE';
  end_pin;
  body
    PART_NAME='GTL2014PW';
    BODY_NAME='GTL2014PW';
    PHYS_DES_PREFIX='U';
    CLASS='IC';
  end_body;
end_primitive;

END.
